(kicad_pcb
	(version 20260206)
	(generator "pcbnew")
	(generator_version "10.0")
	(general
		(thickness 1.6)
		(legacy_teardrops no)
	)
	(paper "A4")
	(title_block
		(title "timecard-production-celestica-r4006 — R4006-B0001-02_R01.brd")
		(comment 1 "Time Appliance Project (Time Card) / footprints 284-290 of 1113")
	)
	(layers
		(0 "F.Cu" signal "TOP")
		(4 "In1.Cu" signal "L02_GND1")
		(6 "In2.Cu" signal "L03_SIG1")
		(8 "In3.Cu" signal "L04_GND2")
		(10 "In4.Cu" signal "L05_VCC1")
		(12 "In5.Cu" signal "L06_VCC2")
		(14 "In6.Cu" signal "L07_GND3")
		(16 "In7.Cu" signal "L08_SIG2")
		(18 "In8.Cu" signal "L09_GND4")
		(2 "B.Cu" signal "BOTTOM")
		(9 "F.Adhes" user "F.Adhesive")
		(11 "B.Adhes" user "B.Adhesive")
		(13 "F.Paste" user "Package Geometry/Pastemask Top")
		(15 "B.Paste" user "Package Geometry/Pastemask Bottom")
		(5 "F.SilkS" user "Ref Des/Silkscreen Top")
		(7 "B.SilkS" user "Ref Des/Silkscreen Bottom")
		(1 "F.Mask" user "Board Geometry/Soldermask Top")
		(3 "B.Mask" user "Board Geometry/Soldermask Bottom")
		(17 "Dwgs.User" user "User.Drawings")
		(19 "Cmts.User" user "User.Comments")
		(21 "Eco1.User" user "User.Eco1")
		(23 "Eco2.User" user "User.Eco2")
		(25 "Edge.Cuts" user "Board Geometry/Outline")
		(27 "Margin" user)
		(31 "F.CrtYd" user "Package Geometry/Place Bound Top")
		(29 "B.CrtYd" user "Package Geometry/Place Bound Bottom")
		(35 "F.Fab" user "Ref Des/Assembly Top")
		(33 "B.Fab" user "Ref Des/Assembly Bottom")
	)
	(footprint ""
		(layer "F.Cu")
		(at 146.1516 -59.563 -90)
		(property "Reference" "R255"
			(at 1.016 -1.84277 90)
			(unlocked yes)
			(layer "F.SilkS")
			(effects
				(font
					(size 0.7874 0.5842)
					(thickness 0.1524)
				)
			)
		)
		(property "Value" "VAL*"
			(at 0.02032 2.13233 270)
			(unlocked yes)
			(layer "F.Fab")
			(hide yes)
			(effects
				(font
					(size 0.7874 0.5842)
					(thickness 0.1524)
				)
			)
		)
		(property "Device Type" "RESISTOR-G155-02262-01,22.6K,1%"
			(at 0.008382 1.210564 270)
			(unlocked yes)
			(layer "F.Fab")
			(hide yes)
			(effects
				(font
					(size 0.7874 0.5842)
					(thickness 0.1524)
				)
			)
		)
		(property "User Part Number" "PARTNUM*"
			(at 0.02032 4.024884 270)
			(unlocked yes)
			(layer "Cmts.User")
			(hide yes)
			(effects
				(font
					(size 0.7874 0.5842)
					(thickness 0.1524)
				)
			)
		)
		(property "Tolerance" "TOL*"
			(at 0.044704 3.05435 270)
			(unlocked yes)
			(layer "Cmts.User")
			(hide yes)
			(effects
				(font
					(size 0.7874 0.5842)
					(thickness 0.1524)
				)
			)
		)
		(duplicate_pad_numbers_are_jumpers no)
		(fp_line
			(start -1.143 0.5588)
			(end 1.143 0.5588)
			(stroke
				(width 0.1)
				(type default)
			)
			(layer "F.SilkS")
		)
		(fp_line
			(start 1.143 0.5588)
			(end 1.143 -0.5588)
			(stroke
				(width 0.1)
				(type default)
			)
			(layer "F.SilkS")
		)
		(fp_line
			(start -1.143 -0.5588)
			(end -1.143 0.5588)
			(stroke
				(width 0.1)
				(type default)
			)
			(layer "F.SilkS")
		)
		(fp_line
			(start 1.143 -0.5588)
			(end -1.143 -0.5588)
			(stroke
				(width 0.1)
				(type default)
			)
			(layer "F.SilkS")
		)
		(fp_rect
			(start 1.143 0.5588)
			(end -1.143 -0.5588)
			(stroke
				(width 0)
				(type default)
			)
			(fill no)
			(layer "F.CrtYd")
		)
		(fp_line
			(start -0.508 0.3048)
			(end 0.508 0.3048)
			(stroke
				(width 0.1)
				(type default)
			)
			(layer "F.Fab")
		)
		(fp_line
			(start 0.508 0.3048)
			(end 0.508 -0.3048)
			(stroke
				(width 0.1)
				(type default)
			)
			(layer "F.Fab")
		)
		(fp_line
			(start -0.508 -0.3048)
			(end -0.508 0.3048)
			(stroke
				(width 0.1)
				(type default)
			)
			(layer "F.Fab")
		)
		(fp_line
			(start 0.508 -0.3048)
			(end -0.508 -0.3048)
			(stroke
				(width 0.1)
				(type default)
			)
			(layer "F.Fab")
		)
		(pad "1" smd rect
			(at -0.5334 0 270)
			(size 0.7112 0.6096)
			(layers "F.Cu" "F.Mask" "F.Paste")
			(net "UNNAMED_523_CAPACITOR_I28_1")
		)
		(pad "2" smd rect
			(at 0.5334 0 270)
			(size 0.7112 0.6096)
			(layers "F.Cu" "F.Mask" "F.Paste")
			(net "XP1R0V_FB_R_TO_AGND")
		)
		(zone
			(layer "F.Cu")
			(hatch none 0.5)
			(connect_pads
				(clearance 0)
			)
			(min_thickness 0.25)
			(keepout
				(tracks allowed)
				(vias not_allowed)
				(pads allowed)
				(copperpour not_allowed)
				(footprints allowed)
			)
			(placement
				(enabled no)
				(sheetname "")
			)
			(fill
				(thermal_gap 0.5)
				(thermal_bridge_width 0.5)
				(island_removal_mode 0)
			)
			(polygon
				(pts
					(xy 145.8468 -59.4868) (xy 146.4564 -59.4868) (xy 146.4564 -59.6392) (xy 145.8468 -59.6392)
				)
			)
		)
	)
	(footprint ""
		(layer "F.Cu")
		(at 14.732 -22.987 -90)
		(property "Reference" "R368"
			(at 0.635 3.64363 90)
			(unlocked yes)
			(layer "F.SilkS")
			(effects
				(font
					(size 0.7874 0.5842)
					(thickness 0.1524)
				)
			)
		)
		(property "Value" "VAL*"
			(at 0.02032 2.13233 270)
			(unlocked yes)
			(layer "F.Fab")
			(hide yes)
			(effects
				(font
					(size 0.7874 0.5842)
					(thickness 0.1524)
				)
			)
		)
		(property "Tolerance" "TOL*"
			(at 0.044704 3.05435 270)
			(unlocked yes)
			(layer "Cmts.User")
			(hide yes)
			(effects
				(font
					(size 0.7874 0.5842)
					(thickness 0.1524)
				)
			)
		)
		(property "User Part Number" "PARTNUM*"
			(at 0.02032 4.024884 270)
			(unlocked yes)
			(layer "Cmts.User")
			(hide yes)
			(effects
				(font
					(size 0.7874 0.5842)
					(thickness 0.1524)
				)
			)
		)
		(property "Device Type" "RESISTOR-G155-14701-01,4.7KOHMA"
			(at 0.008382 1.210564 270)
			(unlocked yes)
			(layer "F.Fab")
			(hide yes)
			(effects
				(font
					(size 0.7874 0.5842)
					(thickness 0.1524)
				)
			)
		)
		(duplicate_pad_numbers_are_jumpers no)
		(fp_line
			(start -1.143 0.5588)
			(end 1.143 0.5588)
			(stroke
				(width 0.1)
				(type default)
			)
			(layer "F.SilkS")
		)
		(fp_line
			(start 1.143 0.5588)
			(end 1.143 -0.5588)
			(stroke
				(width 0.1)
				(type default)
			)
			(layer "F.SilkS")
		)
		(fp_line
			(start -1.143 -0.5588)
			(end -1.143 0.5588)
			(stroke
				(width 0.1)
				(type default)
			)
			(layer "F.SilkS")
		)
		(fp_line
			(start 1.143 -0.5588)
			(end -1.143 -0.5588)
			(stroke
				(width 0.1)
				(type default)
			)
			(layer "F.SilkS")
		)
		(fp_rect
			(start -1.143 0.5588)
			(end 1.143 -0.5588)
			(stroke
				(width 0)
				(type default)
			)
			(fill no)
			(layer "F.CrtYd")
		)
		(fp_line
			(start -0.508 0.3048)
			(end 0.508 0.3048)
			(stroke
				(width 0.1)
				(type default)
			)
			(layer "F.Fab")
		)
		(fp_line
			(start 0.508 0.3048)
			(end 0.508 -0.3048)
			(stroke
				(width 0.1)
				(type default)
			)
			(layer "F.Fab")
		)
		(fp_line
			(start -0.508 -0.3048)
			(end -0.508 0.3048)
			(stroke
				(width 0.1)
				(type default)
			)
			(layer "F.Fab")
		)
		(fp_line
			(start 0.508 -0.3048)
			(end -0.508 -0.3048)
			(stroke
				(width 0.1)
				(type default)
			)
			(layer "F.Fab")
		)
		(pad "1" smd rect
			(at -0.5334 0 270)
			(size 0.7112 0.6096)
			(layers "F.Cu" "F.Mask" "F.Paste")
			(net "XP3R3V_FPGA")
		)
		(pad "2" smd rect
			(at 0.5334 0 270)
			(size 0.7112 0.6096)
			(layers "F.Cu" "F.Mask" "F.Paste")
			(net "SMA4_SIG_OUT_BF_EN_N")
		)
		(zone
			(layer "F.Cu")
			(hatch none 0.5)
			(connect_pads
				(clearance 0)
			)
			(min_thickness 0.25)
			(keepout
				(tracks not_allowed)
				(vias allowed)
				(pads allowed)
				(copperpour not_allowed)
				(footprints allowed)
			)
			(placement
				(enabled no)
				(sheetname "")
			)
			(fill
				(thermal_gap 0.5)
				(thermal_bridge_width 0.5)
				(island_removal_mode 0)
			)
			(polygon
				(pts
					(xy 14.4272 -23.0632) (xy 14.4272 -22.9108) (xy 15.0368 -22.9108) (xy 15.0368 -23.0632)
				)
			)
		)
		(zone
			(layer "F.Cu")
			(hatch none 0.5)
			(connect_pads
				(clearance 0)
			)
			(min_thickness 0.25)
			(keepout
				(tracks allowed)
				(vias not_allowed)
				(pads allowed)
				(copperpour not_allowed)
				(footprints allowed)
			)
			(placement
				(enabled no)
				(sheetname "")
			)
			(fill
				(thermal_gap 0.5)
				(thermal_bridge_width 0.5)
				(island_removal_mode 0)
			)
			(polygon
				(pts
					(xy 14.4272 -23.0632) (xy 14.4272 -22.9108) (xy 15.0368 -22.9108) (xy 15.0368 -23.0632)
				)
			)
		)
	)
	(footprint ""
		(layer "F.Cu")
		(at 32.021018 -26.426922)
		(property "Reference" "MAC_PIN3"
			(at -2.176018 -2.621026 0)
			(unlocked yes)
			(layer "F.SilkS")
			(effects
				(font
					(size 0.7874 0.5842)
					(thickness 0.1524)
				)
			)
		)
		(property "Value" ""
			(at 0 0 0)
			(layer "F.Fab")
			(effects
				(font
					(size 1.27 1.27)
				)
			)
		)
		(property "User Part Number" "PARTNUM*"
			(at 0 3.826764 0)
			(unlocked yes)
			(layer "Cmts.User")
			(hide yes)
			(effects
				(font
					(size 0.7874 0.5842)
					(thickness 0.1524)
				)
			)
		)
		(property "Device Type" "NUT-A200-00029-FB"
			(at 0 2.632964 0)
			(unlocked yes)
			(layer "F.Fab")
			(hide yes)
			(effects
				(font
					(size 0.7874 0.5842)
					(thickness 0.1524)
				)
			)
		)
		(duplicate_pad_numbers_are_jumpers no)
		(fp_circle
			(center 0 0)
			(end 1.524 0)
			(stroke
				(width 0.1)
				(type default)
			)
			(fill no)
			(layer "F.SilkS")
		)
		(fp_poly
			(pts
				(arc
					(start -1.260856 -0.1524)
					(mid -0.898049 -0.898049)
					(end -0.1524 -1.260856)
				)
				(arc
					(start -0.1524 -0.991616)
					(mid -0.709411 -0.709411)
					(end -0.991616 -0.1524)
				)
			)
			(stroke
				(width 0)
				(type default)
			)
			(fill yes)
			(layer "F.Paste")
		)
		(fp_poly
			(pts
				(arc
					(start -0.1524 1.260856)
					(mid -0.898049 0.898049)
					(end -1.260856 0.1524)
				)
				(arc
					(start -0.991616 0.1524)
					(mid -0.709411 0.709411)
					(end -0.1524 0.991616)
				)
			)
			(stroke
				(width 0)
				(type default)
			)
			(fill yes)
			(layer "F.Paste")
		)
		(fp_poly
			(pts
				(arc
					(start 0.1524 -1.260856)
					(mid 0.898049 -0.898049)
					(end 1.260856 -0.1524)
				)
				(arc
					(start 0.991616 -0.1524)
					(mid 0.709411 -0.709411)
					(end 0.1524 -0.991616)
				)
			)
			(stroke
				(width 0)
				(type default)
			)
			(fill yes)
			(layer "F.Paste")
		)
		(fp_poly
			(pts
				(arc
					(start 1.260856 0.1524)
					(mid 0.898049 0.898049)
					(end 0.1524 1.260856)
				)
				(arc
					(start 0.1524 0.991616)
					(mid 0.709411 0.709411)
					(end 0.991616 0.1524)
				)
			)
			(stroke
				(width 0)
				(type default)
			)
			(fill yes)
			(layer "F.Paste")
		)
		(fp_poly
			(pts
				(arc
					(start 6.35 0)
					(mid -6.35 0)
					(end 6.35 0)
				)
			)
			(stroke
				(width 0)
				(type default)
			)
			(fill no)
			(layer "B.CrtYd")
		)
		(fp_poly
			(pts
				(arc
					(start 1.778 0)
					(mid -1.778 0)
					(end 1.778 0)
				)
			)
			(stroke
				(width 0)
				(type default)
			)
			(fill no)
			(layer "F.CrtYd")
		)
		(fp_circle
			(center 0 0)
			(end 1.1684 0)
			(stroke
				(width 0.1)
				(type default)
			)
			(fill no)
			(layer "F.Fab")
		)
		(pad "1" thru_hole circle
			(at 0 0)
			(size 2.54 2.54)
			(drill 2.0066)
			(layers "*.Cu" "*.Mask")
			(remove_unused_layers no)
			(net "R_MAC_10MHZ_RF_OUT")
			(thermal_gap 0.0254)
			(padstack
				(mode front_inner_back)
				(layer "Inner"
					(shape circle)
					(size 2.54 2.54)
					(clearance 0.0254)
				)
				(layer "B.Cu"
					(shape circle)
					(size 2.54 2.54)
				)
			)
		)
	)
	(footprint ""
		(layer "F.Cu")
		(at 127.889 -37.846)
		(property "Reference" "TP138"
			(at 2.26695 2.3749 90)
			(unlocked yes)
			(layer "F.SilkS")
			(effects
				(font
					(size 0.635 0.4064)
					(thickness 0.1524)
				)
				(justify left)
			)
		)
		(property "Value" ""
			(at 0 0 0)
			(layer "F.Fab")
			(effects
				(font
					(size 1.27 1.27)
				)
			)
		)
		(property "Device Type" "TP_PIONT-TP010CT020B030_PTH-TPA"
			(at -1.341882 0.996696 0)
			(unlocked yes)
			(layer "F.Fab")
			(hide yes)
			(effects
				(font
					(size 0.7874 0.5842)
					(thickness 0.1524)
				)
				(justify left)
			)
		)
		(duplicate_pad_numbers_are_jumpers no)
		(fp_poly
			(pts
				(arc
					(start 0.889 0)
					(mid -0.889 0)
					(end 0.889 0)
				)
			)
			(stroke
				(width 0)
				(type default)
			)
			(fill no)
			(layer "B.CrtYd")
		)
		(fp_poly
			(pts
				(arc
					(start 0.889 0)
					(mid -0.889 0)
					(end 0.889 0)
				)
			)
			(stroke
				(width 0)
				(type default)
			)
			(fill no)
			(layer "F.CrtYd")
		)
		(pad "1" thru_hole circle
			(at 0 0)
			(size 0.508 0.508)
			(drill 0.254)
			(layers "*.Cu" "*.Mask")
			(remove_unused_layers no)
			(net "IO_L23P_34")
			(clearance 0.1016)
			(padstack
				(mode front_inner_back)
				(layer "Inner"
					(shape circle)
					(size 0.508 0.508)
					(clearance 0.1016)
				)
				(layer "B.Cu"
					(shape circle)
					(size 0.762 0.762)
					(clearance -0.0254)
				)
			)
		)
	)
	(footprint ""
		(layer "F.Cu")
		(at 90.932 -66.421)
		(property "Reference" "TP58"
			(at -1.6764 -1.11125 0)
			(unlocked yes)
			(layer "F.SilkS")
			(effects
				(font
					(size 0.635 0.4064)
					(thickness 0.1524)
				)
				(justify left)
			)
		)
		(property "Value" ""
			(at 0 0 0)
			(layer "F.Fab")
			(effects
				(font
					(size 1.27 1.27)
				)
			)
		)
		(property "Device Type" "TP_PIONT-TP010CT020B030_PTH-TPA"
			(at -1.341882 0.996696 0)
			(unlocked yes)
			(layer "F.Fab")
			(hide yes)
			(effects
				(font
					(size 0.7874 0.5842)
					(thickness 0.1524)
				)
				(justify left)
			)
		)
		(duplicate_pad_numbers_are_jumpers no)
		(fp_poly
			(pts
				(arc
					(start 0.889 0)
					(mid -0.889 0)
					(end 0.889 0)
				)
			)
			(stroke
				(width 0)
				(type default)
			)
			(fill no)
			(layer "B.CrtYd")
		)
		(fp_poly
			(pts
				(arc
					(start 0.889 0)
					(mid -0.889 0)
					(end 0.889 0)
				)
			)
			(stroke
				(width 0)
				(type default)
			)
			(fill no)
			(layer "F.CrtYd")
		)
		(pad "1" thru_hole circle
			(at 0 0)
			(size 0.508 0.508)
			(drill 0.254)
			(layers "*.Cu" "*.Mask")
			(remove_unused_layers no)
			(net "XP3R3V_FPGA")
			(clearance 0.1016)
			(padstack
				(mode front_inner_back)
				(layer "Inner"
					(shape circle)
					(size 0.508 0.508)
					(clearance 0.1016)
				)
				(layer "B.Cu"
					(shape circle)
					(size 0.762 0.762)
					(clearance -0.0254)
				)
			)
		)
	)
	(footprint ""
		(layer "F.Cu")
		(at 55.5244 -103.4034 90)
		(property "Reference" "C14"
			(at 0 3.84937 90)
			(unlocked yes)
			(layer "F.SilkS")
			(effects
				(font
					(size 0.7874 0.5842)
					(thickness 0.1524)
				)
			)
		)
		(property "Value" "VAL*"
			(at 0.0762 3.134106 90)
			(unlocked yes)
			(layer "F.Fab")
			(hide yes)
			(effects
				(font
					(size 0.7874 0.5842)
					(thickness 0.1524)
				)
			)
		)
		(property "Device Type" "CAPACITOR-G107-0F226-CM,22UF,2A"
			(at 0.0508 2.194306 90)
			(unlocked yes)
			(layer "F.Fab")
			(hide yes)
			(effects
				(font
					(size 0.7874 0.5842)
					(thickness 0.1524)
				)
			)
		)
		(property "User Part Number" "PARTNUM*"
			(at 0.1016 5.013706 90)
			(unlocked yes)
			(layer "Cmts.User")
			(hide yes)
			(effects
				(font
					(size 0.7874 0.5842)
					(thickness 0.1524)
				)
			)
		)
		(property "Tolerance" "TOL*"
			(at 0.0762 4.048506 90)
			(unlocked yes)
			(layer "Cmts.User")
			(hide yes)
			(effects
				(font
					(size 0.7874 0.5842)
					(thickness 0.1524)
				)
			)
		)
		(duplicate_pad_numbers_are_jumpers no)
		(fp_line
			(start 1.5748 -0.9398)
			(end -1.5748 -0.9398)
			(stroke
				(width 0.1)
				(type default)
			)
			(layer "F.SilkS")
		)
		(fp_line
			(start -1.5748 -0.9398)
			(end -1.5748 0.9398)
			(stroke
				(width 0.1)
				(type default)
			)
			(layer "F.SilkS")
		)
		(fp_line
			(start 1.5748 0.9398)
			(end 1.5748 -0.9398)
			(stroke
				(width 0.1)
				(type default)
			)
			(layer "F.SilkS")
		)
		(fp_line
			(start -1.5748 0.9398)
			(end 1.5748 0.9398)
			(stroke
				(width 0.1)
				(type default)
			)
			(layer "F.SilkS")
		)
		(fp_rect
			(start 1.5748 0.9398)
			(end -1.5748 -0.9398)
			(stroke
				(width 0)
				(type default)
			)
			(fill no)
			(layer "F.CrtYd")
		)
		(fp_line
			(start 1.016 -0.635)
			(end -1.016 -0.635)
			(stroke
				(width 0.1)
				(type default)
			)
			(layer "F.Fab")
		)
		(fp_line
			(start -1.016 -0.635)
			(end -1.016 0.635)
			(stroke
				(width 0.1)
				(type default)
			)
			(layer "F.Fab")
		)
		(fp_line
			(start 1.016 0.635)
			(end 1.016 -0.635)
			(stroke
				(width 0.1)
				(type default)
			)
			(layer "F.Fab")
		)
		(fp_line
			(start -1.016 0.635)
			(end 1.016 0.635)
			(stroke
				(width 0.1)
				(type default)
			)
			(layer "F.Fab")
		)
		(pad "1" smd rect
			(at -0.8382 0 90)
			(size 0.9652 1.3716)
			(layers "F.Cu" "F.Mask" "F.Paste")
			(net "XP5R0V")
		)
		(pad "2" smd rect
			(at 0.8382 0 90)
			(size 0.9652 1.3716)
			(layers "F.Cu" "F.Mask" "F.Paste")
			(net "SG")
		)
		(zone
			(layer "F.Cu")
			(hatch none 0.5)
			(connect_pads
				(clearance 0)
			)
			(min_thickness 0.25)
			(keepout
				(tracks allowed)
				(vias not_allowed)
				(pads allowed)
				(copperpour not_allowed)
				(footprints allowed)
			)
			(placement
				(enabled no)
				(sheetname "")
			)
			(fill
				(thermal_gap 0.5)
				(thermal_bridge_width 0.5)
				(island_removal_mode 0)
			)
			(polygon
				(pts
					(xy 56.1594 -103.632) (xy 54.8894 -103.632) (xy 54.8894 -103.1748) (xy 56.1594 -103.1748)
				)
			)
		)
	)
	(footprint ""
		(layer "F.Cu")
		(at 153.67 -57.658)
		(property "Reference" "C275"
			(at 1.905 2.32537 0)
			(unlocked yes)
			(layer "F.SilkS")
			(effects
				(font
					(size 0.7874 0.5842)
					(thickness 0.1524)
				)
			)
		)
		(property "Value" "VAL*"
			(at 0.0762 2.067306 0)
			(unlocked yes)
			(layer "F.Fab")
			(hide yes)
			(effects
				(font
					(size 0.7874 0.5842)
					(thickness 0.1524)
				)
			)
		)
		(property "Tolerance" "TOL*"
			(at 0.0762 3.032506 0)
			(unlocked yes)
			(layer "Cmts.User")
			(hide yes)
			(effects
				(font
					(size 0.7874 0.5842)
					(thickness 0.1524)
				)
			)
		)
		(property "User Part Number" "PARTNUM*"
			(at 0.1016 4.023106 0)
			(unlocked yes)
			(layer "Cmts.User")
			(hide yes)
			(effects
				(font
					(size 0.7874 0.5842)
					(thickness 0.1524)
				)
			)
		)
		(property "Device Type" "CAPACITOR-G105-0B104-EK,0.1UF,A"
			(at 0.0508 1.127506 0)
			(unlocked yes)
			(layer "F.Fab")
			(hide yes)
			(effects
				(font
					(size 0.7874 0.5842)
					(thickness 0.1524)
				)
			)
		)
		(duplicate_pad_numbers_are_jumpers no)
		(fp_line
			(start -1.143 -0.5588)
			(end -1.143 0.5588)
			(stroke
				(width 0.1)
				(type default)
			)
			(layer "F.SilkS")
		)
		(fp_line
			(start -1.143 0.5588)
			(end 1.143 0.5588)
			(stroke
				(width 0.1)
				(type default)
			)
			(layer "F.SilkS")
		)
		(fp_line
			(start 1.143 -0.5588)
			(end -1.143 -0.5588)
			(stroke
				(width 0.1)
				(type default)
			)
			(layer "F.SilkS")
		)
		(fp_line
			(start 1.143 0.5588)
			(end 1.143 -0.5588)
			(stroke
				(width 0.1)
				(type default)
			)
			(layer "F.SilkS")
		)
		(fp_rect
			(start 1.143 -0.5588)
			(end -1.143 0.5588)
			(stroke
				(width 0)
				(type default)
			)
			(fill no)
			(layer "F.CrtYd")
		)
		(fp_line
			(start -0.508 -0.3048)
			(end -0.508 0.3048)
			(stroke
				(width 0.1)
				(type default)
			)
			(layer "F.Fab")
		)
		(fp_line
			(start -0.508 0.3048)
			(end 0.508 0.3048)
			(stroke
				(width 0.1)
				(type default)
			)
			(layer "F.Fab")
		)
		(fp_line
			(start 0.508 -0.3048)
			(end -0.508 -0.3048)
			(stroke
				(width 0.1)
				(type default)
			)
			(layer "F.Fab")
		)
		(fp_line
			(start 0.508 0.3048)
			(end 0.508 -0.3048)
			(stroke
				(width 0.1)
				(type default)
			)
			(layer "F.Fab")
		)
		(pad "1" smd rect
			(at -0.5334 0)
			(size 0.7112 0.6096)
			(layers "F.Cu" "F.Mask" "F.Paste")
			(net "VDD3V3_SHT31A")
		)
		(pad "2" smd rect
			(at 0.5334 0)
			(size 0.7112 0.6096)
			(layers "F.Cu" "F.Mask" "F.Paste")
			(net "SG")
		)
		(zone
			(layer "F.Cu")
			(hatch none 0.5)
			(connect_pads
				(clearance 0)
			)
			(min_thickness 0.25)
			(keepout
				(tracks allowed)
				(vias not_allowed)
				(pads allowed)
				(copperpour not_allowed)
				(footprints allowed)
			)
			(placement
				(enabled no)
				(sheetname "")
			)
			(fill
				(thermal_gap 0.5)
				(thermal_bridge_width 0.5)
				(island_removal_mode 0)
			)
			(polygon
				(pts
					(xy 153.7462 -57.9628) (xy 153.5938 -57.9628) (xy 153.5938 -57.3532) (xy 153.7462 -57.3532)
				)
			)
		)
	)
)
